(kicad_pcb
	(version 20260206)
	(generator "pcbnew")
	(generator_version "10.0")
	(general
		(thickness 1.6)
		(legacy_teardrops no)
	)
	(paper "A4")
	(title_block
		(title "04192023_DAF0TMB3IC0_F0TG_MB_C_brd_V02_OCP.brd")
		(comment 1 "Grand Teton / footprint 2176 of 8354 (J111), pads 1-48 of 48")
	)
	(layers
		(0 "F.Cu" signal "TOP")
		(4 "In1.Cu" signal "GND")
		(6 "In2.Cu" signal "IN1")
		(8 "In3.Cu" signal "GND1")
		(10 "In4.Cu" signal "IN2")
		(12 "In5.Cu" signal "GND2")
		(14 "In6.Cu" signal "IN3")
		(16 "In7.Cu" signal "GND3")
		(18 "In8.Cu" signal "VCC")
		(20 "In9.Cu" signal "VCC1")
		(22 "In10.Cu" signal "GND4")
		(24 "In11.Cu" signal "IN4")
		(26 "In12.Cu" signal "GND5")
		(28 "In13.Cu" signal "IN5")
		(30 "In14.Cu" signal "GND6")
		(32 "In15.Cu" signal "IN6")
		(34 "In16.Cu" signal "GND7")
		(2 "B.Cu" signal "BOTTOM")
		(9 "F.Adhes" user "F.Adhesive")
		(11 "B.Adhes" user "B.Adhesive")
		(13 "F.Paste" user "Package Geometry/Pastemask Top")
		(15 "B.Paste" user "Package Geometry/Pastemask Bottom")
		(5 "F.SilkS" user "Ref Des/Silkscreen Top")
		(7 "B.SilkS" user "Ref Des/Silkscreen Bottom")
		(1 "F.Mask" user "Board Geometry/Soldermask Top")
		(3 "B.Mask" user "Board Geometry/Soldermask Bottom")
		(17 "Dwgs.User" user "User.Drawings")
		(19 "Cmts.User" user "User.Comments")
		(21 "Eco1.User" user "User.Eco1")
		(23 "Eco2.User" user "User.Eco2")
		(25 "Edge.Cuts" user "Board Geometry/Outline")
		(27 "Margin" user)
		(31 "F.CrtYd" user "Package Geometry/Place Bound Top")
		(29 "B.CrtYd" user "Package Geometry/Place Bound Bottom")
		(35 "F.Fab" user "Ref Des/Assembly Top")
		(33 "B.Fab" user "Ref Des/Assembly Bottom")
	)
	(footprint ""
		(layer "F.Cu")
		(at 75.65009 -440.489848)
		(property "Reference" "J111"
			(at 14.3637 23.187152 0)
			(unlocked yes)
			(layer "F.SilkS")
			(effects
				(font
					(size 0.7874 0.5842)
					(thickness 0.1524)
				)
				(justify left)
			)
		)
		(property "Value" ""
			(at 0 0 0)
			(layer "F.Fab")
			(effects
				(font
					(size 1.27 1.27)
				)
			)
		)
		(duplicate_pad_numbers_are_jumpers no)
		(pad "A1" thru_hole rect
			(at 0 0 180)
			(size 0.766318 0.766318)
			(drill 0.359918)
			(layers "*.Cu" "*.Mask")
			(remove_unused_layers no)
			(net "GPU_PEX_STRAP1")
			(clearance 0.0508)
			(thermal_gap 0.0508)
			(padstack
				(mode front_inner_back)
				(layer "Inner"
					(shape circle)
					(size 0.766318 0.766318)
					(clearance 0.0508)
				)
				(layer "B.Cu"
					(shape rect)
					(size 0.766318 0.766318)
					(clearance 0.0508)
				)
			)
		)
		(pad "A2" thru_hole circle
			(at 1.999996 0.199898 180)
			(size 0.906272 0.906272)
			(drill 0.499872)
			(layers "*.Cu" "*.Mask")
			(remove_unused_layers no)
			(net "GND")
			(clearance 0.0508)
			(thermal_gap 0.0508)
		)
		(pad "A3" thru_hole circle
			(at 3.999992 0 180)
			(size 0.766318 0.766318)
			(drill 0.359918)
			(layers "*.Cu" "*.Mask")
			(remove_unused_layers no)
			(net "GPU_BASE_ID0")
			(clearance 0.0508)
			(thermal_gap 0.0508)
		)
		(pad "A4" thru_hole circle
			(at 5.999988 0.199898 180)
			(size 0.906272 0.906272)
			(drill 0.499872)
			(layers "*.Cu" "*.Mask")
			(remove_unused_layers no)
			(net "GND")
			(clearance 0.0508)
			(thermal_gap 0.0508)
		)
		(pad "A5" thru_hole circle
			(at 7.999984 0 180)
			(size 0.766318 0.766318)
			(drill 0.359918)
			(layers "*.Cu" "*.Mask")
			(remove_unused_layers no)
			(net "GPU_PEX_STRAP0")
			(clearance 0.0508)
			(thermal_gap 0.0508)
		)
		(pad "A6" thru_hole circle
			(at 9.99998 0.199898 180)
			(size 0.906272 0.906272)
			(drill 0.499872)
			(layers "*.Cu" "*.Mask")
			(remove_unused_layers no)
			(net "GND")
			(clearance 0.0508)
			(thermal_gap 0.0508)
		)
		(pad "A7" thru_hole circle
			(at 11.999976 0 180)
			(size 0.766318 0.766318)
			(drill 0.359918)
			(layers "*.Cu" "*.Mask")
			(remove_unused_layers no)
			(net "GPU_FPGA_RST_R_BUF_N")
			(clearance 0.0508)
			(thermal_gap 0.0508)
		)
		(pad "A8" thru_hole circle
			(at 13.999972 0.199898 180)
			(size 0.906272 0.906272)
			(drill 0.499872)
			(layers "*.Cu" "*.Mask")
			(remove_unused_layers no)
			(net "GND")
			(clearance 0.0508)
			(thermal_gap 0.0508)
		)
		(pad "B1" thru_hole circle
			(at 0 1.199896 180)
			(size 0.906272 0.906272)
			(drill 0.499872)
			(layers "*.Cu" "*.Mask")
			(remove_unused_layers no)
			(net "GND")
			(clearance 0.0508)
			(thermal_gap 0.0508)
		)
		(pad "B3" thru_hole circle
			(at 3.999992 1.199896 180)
			(size 0.906272 0.906272)
			(drill 0.499872)
			(layers "*.Cu" "*.Mask")
			(remove_unused_layers no)
			(net "GND")
			(clearance 0.0508)
			(thermal_gap 0.0508)
		)
		(pad "B5" thru_hole circle
			(at 7.999984 1.199896 180)
			(size 0.906272 0.906272)
			(drill 0.499872)
			(layers "*.Cu" "*.Mask")
			(remove_unused_layers no)
			(net "GND")
			(clearance 0.0508)
			(thermal_gap 0.0508)
		)
		(pad "B7" thru_hole circle
			(at 11.999976 1.199896 180)
			(size 0.906272 0.906272)
			(drill 0.499872)
			(layers "*.Cu" "*.Mask")
			(remove_unused_layers no)
			(net "GND")
			(clearance 0.0508)
			(thermal_gap 0.0508)
		)
		(pad "D2" thru_hole circle
			(at 1.999996 3.800094 180)
			(size 0.906272 0.906272)
			(drill 0.499872)
			(layers "*.Cu" "*.Mask")
			(remove_unused_layers no)
			(net "GND")
			(clearance 0.0508)
			(thermal_gap 0.0508)
		)
		(pad "D4" thru_hole circle
			(at 5.999988 3.800094 180)
			(size 0.906272 0.906272)
			(drill 0.499872)
			(layers "*.Cu" "*.Mask")
			(remove_unused_layers no)
			(net "GND")
			(clearance 0.0508)
			(thermal_gap 0.0508)
		)
		(pad "D6" thru_hole circle
			(at 9.99998 3.800094 180)
			(size 0.906272 0.906272)
			(drill 0.499872)
			(layers "*.Cu" "*.Mask")
			(remove_unused_layers no)
			(net "GND")
			(clearance 0.0508)
			(thermal_gap 0.0508)
		)
		(pad "D8" thru_hole circle
			(at 13.999972 3.800094 180)
			(size 0.906272 0.906272)
			(drill 0.499872)
			(layers "*.Cu" "*.Mask")
			(remove_unused_layers no)
			(net "GND")
			(clearance 0.0508)
			(thermal_gap 0.0508)
		)
		(pad "E1" thru_hole circle
			(at 0 4.800092 180)
			(size 0.906272 0.906272)
			(drill 0.499872)
			(layers "*.Cu" "*.Mask")
			(remove_unused_layers no)
			(net "GND")
			(clearance 0.0508)
			(thermal_gap 0.0508)
		)
		(pad "E3" thru_hole circle
			(at 3.999992 4.800092 180)
			(size 0.906272 0.906272)
			(drill 0.499872)
			(layers "*.Cu" "*.Mask")
			(remove_unused_layers no)
			(net "GND")
			(clearance 0.0508)
			(thermal_gap 0.0508)
		)
		(pad "E5" thru_hole circle
			(at 7.999984 4.800092 180)
			(size 0.906272 0.906272)
			(drill 0.499872)
			(layers "*.Cu" "*.Mask")
			(remove_unused_layers no)
			(net "GND")
			(clearance 0.0508)
			(thermal_gap 0.0508)
		)
		(pad "E7" thru_hole circle
			(at 11.999976 4.800092 180)
			(size 0.906272 0.906272)
			(drill 0.499872)
			(layers "*.Cu" "*.Mask")
			(remove_unused_layers no)
			(net "GND")
			(clearance 0.0508)
			(thermal_gap 0.0508)
		)
		(pad "G2" thru_hole circle
			(at 1.999996 7.400036 180)
			(size 0.906272 0.906272)
			(drill 0.499872)
			(layers "*.Cu" "*.Mask")
			(remove_unused_layers no)
			(net "GND")
			(clearance 0.0508)
			(thermal_gap 0.0508)
		)
		(pad "G4" thru_hole circle
			(at 5.999988 7.400036 180)
			(size 0.906272 0.906272)
			(drill 0.499872)
			(layers "*.Cu" "*.Mask")
			(remove_unused_layers no)
			(net "GND")
			(clearance 0.0508)
			(thermal_gap 0.0508)
		)
		(pad "G6" thru_hole circle
			(at 9.99998 7.400036 180)
			(size 0.906272 0.906272)
			(drill 0.499872)
			(layers "*.Cu" "*.Mask")
			(remove_unused_layers no)
			(net "GND")
			(clearance 0.0508)
			(thermal_gap 0.0508)
		)
		(pad "G8" thru_hole circle
			(at 13.999972 7.400036 180)
			(size 0.906272 0.906272)
			(drill 0.499872)
			(layers "*.Cu" "*.Mask")
			(remove_unused_layers no)
			(net "GND")
			(clearance 0.0508)
			(thermal_gap 0.0508)
		)
		(pad "H1" thru_hole circle
			(at 0 8.400034 180)
			(size 0.906272 0.906272)
			(drill 0.499872)
			(layers "*.Cu" "*.Mask")
			(remove_unused_layers no)
			(net "GND")
			(clearance 0.0508)
			(thermal_gap 0.0508)
		)
		(pad "H3" thru_hole circle
			(at 3.999992 8.400034 180)
			(size 0.906272 0.906272)
			(drill 0.499872)
			(layers "*.Cu" "*.Mask")
			(remove_unused_layers no)
			(net "GND")
			(clearance 0.0508)
			(thermal_gap 0.0508)
		)
		(pad "H5" thru_hole circle
			(at 7.999984 8.400034 180)
			(size 0.906272 0.906272)
			(drill 0.499872)
			(layers "*.Cu" "*.Mask")
			(remove_unused_layers no)
			(net "GND")
			(clearance 0.0508)
			(thermal_gap 0.0508)
		)
		(pad "H7" thru_hole circle
			(at 11.999976 8.400034 180)
			(size 0.906272 0.906272)
			(drill 0.499872)
			(layers "*.Cu" "*.Mask")
			(remove_unused_layers no)
			(net "GND")
			(clearance 0.0508)
			(thermal_gap 0.0508)
		)
		(pad "J2" thru_hole circle
			(at 1.999996 10.999978 180)
			(size 0.906272 0.906272)
			(drill 0.499872)
			(layers "*.Cu" "*.Mask")
			(remove_unused_layers no)
			(net "GND")
			(clearance 0.0508)
			(thermal_gap 0.0508)
		)
		(pad "J4" thru_hole circle
			(at 5.999988 10.999978 180)
			(size 0.906272 0.906272)
			(drill 0.499872)
			(layers "*.Cu" "*.Mask")
			(remove_unused_layers no)
			(net "GND")
			(clearance 0.0508)
			(thermal_gap 0.0508)
		)
		(pad "J6" thru_hole circle
			(at 9.99998 10.999978 180)
			(size 0.906272 0.906272)
			(drill 0.499872)
			(layers "*.Cu" "*.Mask")
			(remove_unused_layers no)
			(net "GND")
			(clearance 0.0508)
			(thermal_gap 0.0508)
		)
		(pad "J8" thru_hole circle
			(at 13.999972 10.999978 180)
			(size 0.906272 0.906272)
			(drill 0.499872)
			(layers "*.Cu" "*.Mask")
			(remove_unused_layers no)
			(net "GND")
			(clearance 0.0508)
			(thermal_gap 0.0508)
		)
		(pad "K1" thru_hole circle
			(at 0 11.999976 180)
			(size 0.906272 0.906272)
			(drill 0.499872)
			(layers "*.Cu" "*.Mask")
			(remove_unused_layers no)
			(net "GND")
			(clearance 0.0508)
			(thermal_gap 0.0508)
		)
		(pad "K3" thru_hole circle
			(at 3.999992 11.999976 180)
			(size 0.906272 0.906272)
			(drill 0.499872)
			(layers "*.Cu" "*.Mask")
			(remove_unused_layers no)
			(net "GND")
			(clearance 0.0508)
			(thermal_gap 0.0508)
		)
		(pad "K5" thru_hole circle
			(at 7.999984 11.999976 180)
			(size 0.906272 0.906272)
			(drill 0.499872)
			(layers "*.Cu" "*.Mask")
			(remove_unused_layers no)
			(net "GND")
			(clearance 0.0508)
			(thermal_gap 0.0508)
		)
		(pad "K7" thru_hole circle
			(at 11.999976 11.999976 180)
			(size 0.906272 0.906272)
			(drill 0.499872)
			(layers "*.Cu" "*.Mask")
			(remove_unused_layers no)
			(net "GND")
			(clearance 0.0508)
			(thermal_gap 0.0508)
		)
		(pad "M2" thru_hole circle
			(at 1.999996 14.59992 180)
			(size 0.906272 0.906272)
			(drill 0.499872)
			(layers "*.Cu" "*.Mask")
			(remove_unused_layers no)
			(net "GND")
			(clearance 0.0508)
			(thermal_gap 0.0508)
		)
		(pad "M4" thru_hole circle
			(at 5.999988 14.59992 180)
			(size 0.906272 0.906272)
			(drill 0.499872)
			(layers "*.Cu" "*.Mask")
			(remove_unused_layers no)
			(net "GND")
			(clearance 0.0508)
			(thermal_gap 0.0508)
		)
		(pad "M6" thru_hole circle
			(at 9.99998 14.59992 180)
			(size 0.906272 0.906272)
			(drill 0.499872)
			(layers "*.Cu" "*.Mask")
			(remove_unused_layers no)
			(net "GND")
			(clearance 0.0508)
			(thermal_gap 0.0508)
		)
		(pad "M8" thru_hole circle
			(at 13.999972 14.59992 180)
			(size 0.906272 0.906272)
			(drill 0.499872)
			(layers "*.Cu" "*.Mask")
			(remove_unused_layers no)
			(net "GND")
			(clearance 0.0508)
			(thermal_gap 0.0508)
		)
		(pad "N1" thru_hole circle
			(at 0 15.599918 180)
			(size 0.906272 0.906272)
			(drill 0.499872)
			(layers "*.Cu" "*.Mask")
			(remove_unused_layers no)
			(net "GND")
			(clearance 0.0508)
			(thermal_gap 0.0508)
		)
		(pad "N2" thru_hole circle
			(at 1.999996 15.80007 180)
			(size 0.766318 0.766318)
			(drill 0.359918)
			(layers "*.Cu" "*.Mask")
			(remove_unused_layers no)
			(net "GPU_PRSNT_N")
			(clearance 0.0508)
			(thermal_gap 0.0508)
		)
		(pad "N3" thru_hole circle
			(at 3.999992 15.599918 180)
			(size 0.906272 0.906272)
			(drill 0.499872)
			(layers "*.Cu" "*.Mask")
			(remove_unused_layers no)
			(net "GND")
			(clearance 0.0508)
			(thermal_gap 0.0508)
		)
		(pad "N4" thru_hole circle
			(at 5.999988 15.80007 180)
			(size 0.766318 0.766318)
			(drill 0.359918)
			(layers "*.Cu" "*.Mask")
			(remove_unused_layers no)
			(net "FM_GPU_PWR_EN_R_BUF")
			(clearance 0.0508)
			(thermal_gap 0.0508)
		)
		(pad "N5" thru_hole circle
			(at 7.999984 15.599918 180)
			(size 0.906272 0.906272)
			(drill 0.499872)
			(layers "*.Cu" "*.Mask")
			(remove_unused_layers no)
			(net "GND")
			(clearance 0.0508)
			(thermal_gap 0.0508)
		)
		(pad "N6" thru_hole circle
			(at 9.99998 15.80007 180)
			(size 0.766318 0.766318)
			(drill 0.359918)
			(layers "*.Cu" "*.Mask")
			(remove_unused_layers no)
			(net "FM_GPU_PWRGD")
			(clearance 0.0508)
			(thermal_gap 0.0508)
		)
		(pad "N7" thru_hole circle
			(at 11.999976 15.599918 180)
			(size 0.906272 0.906272)
			(drill 0.499872)
			(layers "*.Cu" "*.Mask")
			(remove_unused_layers no)
			(net "GND")
			(clearance 0.0508)
			(thermal_gap 0.0508)
		)
		(pad "N8" thru_hole circle
			(at 13.999972 15.80007 180)
			(size 0.766318 0.766318)
			(drill 0.359918)
			(layers "*.Cu" "*.Mask")
			(remove_unused_layers no)
			(net "GPU_BASE_ID1")
			(clearance 0.0508)
			(thermal_gap 0.0508)
		)
	)
)
